(kicad_pcb
	(version 20211014)
	(generator pcbnew)
	(general
    (thickness 1.6)
  )
	(paper "A4")
	(title_block
    (title "SA800U (Snapdragon 845) Baseboard")
    (date "2023-10-19")
    (rev "1.0.3")
    (company "Antmicro Ltd.")
    (comment 1 "www.antmicro.com")
		(comment 9 "footprints 416-421 of 589")
	)
	(layers
    (0 "F.Cu" signal)
    (1 "In1.Cu" power)
    (2 "In2.Cu" signal)
    (3 "In3.Cu" signal)
    (4 "In4.Cu" power)
    (31 "B.Cu" signal)
    (32 "B.Adhes" user "B.Adhesive")
    (33 "F.Adhes" user "F.Adhesive")
    (34 "B.Paste" user)
    (35 "F.Paste" user)
    (36 "B.SilkS" user "B.Silkscreen")
    (37 "F.SilkS" user "F.Silkscreen")
    (38 "B.Mask" user)
    (39 "F.Mask" user)
    (40 "Dwgs.User" user "User.Drawings")
    (41 "Cmts.User" user "User.Comments")
    (42 "Eco1.User" user "User.Eco1")
    (43 "Eco2.User" user "User.Eco2")
    (44 "Edge.Cuts" user)
    (45 "Margin" user)
    (46 "B.CrtYd" user "B.Courtyard")
    (47 "F.CrtYd" user "F.Courtyard")
    (48 "B.Fab" user)
    (49 "F.Fab" user)
  )
	(footprint "sa800u-baseboard-hw-footprints:C_0402_1005Metric" (layer "B.Cu")
    (tedit 616D63CF)
    (at 128.1 142.25 180)
    (descr "Capacitor SMD 0402")
    (tags "capacitor SMD 0402")
    (property "Author" "Antmicro")
    (property "Dielectric" "C0G")
    (property "License" "Apache-2.0")
    (property "MPN" "GRM1555C1E470JA01D")
    (property "Manufacturer" "Murata")
    (property "Sheetfile" "usb-c-interface.kicad_sch")
    (property "Sheetname" "USB-C Interface ")
    (property "Val" "47p")
    (property "Voltage" "")
    (attr smd)
    (fp_text reference "C70" (at -1.07 0.63) (layer "B.SilkS")
      (effects (font (size 0.7 0.7) (thickness 0.15)) (justify left bottom mirror))
    )
    (fp_text value "C_47p_0402" (at 0 -1.4) (layer "B.Fab")
      (effects (font (size 0.7 0.7) (thickness 0.15)) (justify left bottom mirror))
    )
    (fp_text user "${REFERENCE}" (at -0.932 -3.168) (layer "B.Fab") hide
      (effects (font (size 0.7 0.7) (thickness 0.15)) (justify left bottom mirror))
    )
    (fp_text user "License: Apache-2.0" (at -0.932 -5.17) (layer "B.Fab") hide
      (effects (font (size 0.7 0.7) (thickness 0.15)) (justify left bottom mirror))
    )
    (fp_text user "Author: Antmicro" (at -0.932 -4.17) (layer "B.Fab") hide
      (effects (font (size 0.7 0.7) (thickness 0.15)) (justify left bottom mirror))
    )
    (fp_rect (start -0.94 0.47) (end 0.94 -0.47) (layer "B.CrtYd") (width 0.05) (fill none))
    (fp_rect (start -0.499 0.249) (end 0.499 -0.249) (layer "B.Fab") (width 0.15) (fill none))
    (pad "1" smd roundrect (at -0.484 0 180) (size 0.59 0.64) (layers "B.Cu" "B.Paste" "B.Mask") (roundrect_rratio 0.25)
      (net 230 "/USB-C Interface /DBG_USB_D_P") (pintype "passive"))
    (pad "2" smd roundrect (at 0.484 0 180) (size 0.59 0.64) (layers "B.Cu" "B.Paste" "B.Mask") (roundrect_rratio 0.25)
      (net 1 "GND") (pintype "passive"))
  )
	(footprint "sa800u-baseboard-hw-footprints:SOT-23-3" (layer "B.Cu")
    (tedit 5D5D4314)
    (at 94.75 147.3 180)
    (property "Author" "Antmicro")
    (property "License" "Apache-2.0")
    (property "MPN" "BSS84")
    (property "Manufacturer" "ON Semiconductor")
    (property "Sheetfile" "psu.kicad_sch")
    (property "Sheetname" "PSU")
    (attr smd)
    (fp_text reference "Q10" (at 0.88 0.71) (layer "B.SilkS")
      (effects (font (size 0.7 0.7) (thickness 0.15)) (justify left bottom mirror))
    )
    (fp_text value "BSS84" (at -1.9 -2.7) (layer "B.Fab")
      (effects (font (size 0.7 0.7) (thickness 0.15)) (justify left bottom mirror))
    )
    (fp_text user "${REFERENCE}" (at -1.837 -4) (layer "B.Fab") hide
      (effects (font (size 0.7 0.7) (thickness 0.15)) (justify left bottom mirror))
    )
    (fp_text user "Author: Antmicro" (at -1.837 -5.3) (layer "B.Fab") hide
      (effects (font (size 0.7 0.7) (thickness 0.15)) (justify left bottom mirror))
    )
    (fp_text user "License: Apache-2.0" (at -1.8 -6.8) (layer "B.Fab") hide
      (effects (font (size 0.7 0.7) (thickness 0.15)) (justify left bottom mirror))
    )
    (fp_line (start -1.45 1.35) (end -0.85 1.35) (layer "B.SilkS") (width 0.15))
    (fp_line (start 0.7 -1.5) (end -0.7 -1.5) (layer "B.SilkS") (width 0.15))
    (fp_line (start 0.7 1.5) (end -0.7 1.5) (layer "B.SilkS") (width 0.15))
    (fp_line (start 0.7 -0.4) (end 0.7 -1.5) (layer "B.SilkS") (width 0.15))
    (fp_line (start 0.7 0.4) (end 0.7 1.5) (layer "B.SilkS") (width 0.15))
    (fp_line (start -0.7 -1.5) (end -0.7 -1.35) (layer "B.SilkS") (width 0.15))
    (fp_line (start -0.85 1.35) (end -0.7 1.5) (layer "B.SilkS") (width 0.15))
    (fp_line (start -0.85 -1.65) (end -0.85 -1.4) (layer "B.CrtYd") (width 0.05))
    (fp_line (start -1.75 -1.4) (end -1.75 -0.5) (layer "B.CrtYd") (width 0.05))
    (fp_line (start 0.85 -0.45) (end 0.85 -1.65) (layer "B.CrtYd") (width 0.05))
    (fp_line (start -0.85 -1.4) (end -1.75 -1.4) (layer "B.CrtYd") (width 0.05))
    (fp_line (start -0.9 1.4) (end -1.75 1.4) (layer "B.CrtYd") (width 0.05))
    (fp_line (start 0.85 -1.65) (end -0.85 -1.65) (layer "B.CrtYd") (width 0.05))
    (fp_line (start -0.85 0.5) (end -1.75 0.5) (layer "B.CrtYd") (width 0.05))
    (fp_line (start -0.9 1.6) (end 0.825 1.6) (layer "B.CrtYd") (width 0.05))
    (fp_line (start -0.9 1.6) (end -0.9 1.4) (layer "B.CrtYd") (width 0.05))
    (fp_line (start 0.825 1.6) (end 0.825 0.45) (layer "B.CrtYd") (width 0.05))
    (fp_line (start -1.75 -0.5) (end -0.85 -0.5) (layer "B.CrtYd") (width 0.05))
    (fp_line (start -1.75 0.5) (end -1.75 1.4) (layer "B.CrtYd") (width 0.05))
    (fp_line (start 1.75 0.45) (end 1.75 -0.45) (layer "B.CrtYd") (width 0.05))
    (fp_line (start -0.85 -0.5) (end -0.85 0.5) (layer "B.CrtYd") (width 0.05))
    (fp_line (start 0.825 0.45) (end 1.75 0.45) (layer "B.CrtYd") (width 0.05))
    (fp_line (start 1.75 -0.45) (end 0.85 -0.45) (layer "B.CrtYd") (width 0.05))
    (fp_line (start 0.688 -1.519) (end 0.688 1.52) (layer "B.Fab") (width 0.15))
    (fp_line (start -0.437 1.526) (end -0.712 1.325) (layer "B.Fab") (width 0.15))
    (fp_line (start -0.712 -1.519) (end 0.688 -1.519) (layer "B.Fab") (width 0.15))
    (fp_line (start -0.437 1.526) (end 0.688 1.526) (layer "B.Fab") (width 0.15))
    (fp_line (start -0.712 1.325) (end -0.712 -1.523) (layer "B.Fab") (width 0.15))
    (pad "1" smd roundrect (at -1.1 0.951 180) (size 1 0.6) (layers "B.Cu" "B.Paste" "B.Mask") (roundrect_rratio 0.15)
      (net 341 "/PSU/USB_PD_VALID") (pinfunction "G") (pintype "bidirectional"))
    (pad "2" smd roundrect (at -1.1 -0.949 180) (size 1 0.6) (layers "B.Cu" "B.Paste" "B.Mask") (roundrect_rratio 0.15)
      (net 1 "GND") (pinfunction "D") (pintype "bidirectional"))
    (pad "3" smd roundrect (at 1.1 0.0005 180) (size 1 0.6) (layers "B.Cu" "B.Paste" "B.Mask") (roundrect_rratio 0.15)
      (net 389 "Net-(Q10-Pad3)") (pinfunction "S") (pintype "bidirectional"))
  )
	(footprint "sa800u-baseboard-hw-footprints:C_0603_1608Metric" (layer "B.Cu")
    (tedit 5D5E94D2)
    (at 117.5 149.25 -90)
    (descr "Capacitor SMD 0603")
    (tags "capacitor 0603")
    (property "Author" "Antmicro")
    (property "Dielectric" "")
    (property "License" "Apache-2.0")
    (property "MPN" "GRM188R60J476ME15D")
    (property "Manufacturer" "Murata")
    (property "Sheetfile" "usb-c-interface.kicad_sch")
    (property "Sheetname" "USB-C Interface ")
    (property "Val" "47u")
    (property "Voltage" "")
    (attr smd)
    (fp_text reference "C76" (at -1.11 0.78 90) (layer "B.SilkS")
      (effects (font (size 0.7 0.7) (thickness 0.15)) (justify left bottom mirror))
    )
    (fp_text value "C_47u_0603" (at 0 -1.6 90) (layer "B.Fab")
      (effects (font (size 0.7 0.7) (thickness 0.15)) (justify left bottom mirror))
    )
    (fp_text user "License: Apache-2.0" (at -1.682 -5.895 90) (layer "B.Fab") hide
      (effects (font (size 0.7 0.7) (thickness 0.15)) (justify left bottom mirror))
    )
    (fp_text user "Author: Antmicro" (at -1.682 -4.894 90) (layer "B.Fab") hide
      (effects (font (size 0.7 0.7) (thickness 0.15)) (justify left bottom mirror))
    )
    (fp_text user "${REFERENCE}" (at -1.682 -3.895 90) (layer "B.Fab") hide
      (effects (font (size 0.7 0.7) (thickness 0.15)) (justify left bottom mirror))
    )
    (fp_line (start -0.3 -0.3) (end 0.3 -0.3) (layer "B.SilkS") (width 0.15))
    (fp_line (start -0.3 0.3) (end 0.3 0.3) (layer "B.SilkS") (width 0.15))
    (fp_rect (start -1.24 0.7) (end 1.24 -0.7) (layer "B.CrtYd") (width 0.05) (fill none))
    (fp_rect (start -0.8 0.4) (end 0.8 -0.4) (layer "B.Fab") (width 0.15) (fill none))
    (pad "1" smd roundrect (at -0.7 0 270) (size 0.6 0.8) (layers "B.Cu" "B.Paste" "B.Mask") (roundrect_rratio 0.2)
      (net 210 "/USB-C Interface /USB2_5V") (pintype "passive"))
    (pad "2" smd roundrect (at 0.7 0 270) (size 0.6 0.8) (layers "B.Cu" "B.Paste" "B.Mask") (roundrect_rratio 0.2)
      (net 1 "GND") (pintype "passive"))
  )
	(footprint "sa800u-baseboard-hw-footprints:C_0402_1005Metric" (layer "B.Cu")
    (tedit 616D63CF)
    (at 97.5 138.1 90)
    (descr "Capacitor SMD 0402")
    (tags "capacitor SMD 0402")
    (property "Author" "Antmicro")
    (property "Dielectric" "X5R")
    (property "License" "Apache-2.0")
    (property "MPN" "GRM155R61H104KE14D")
    (property "Manufacturer" "Murata")
    (property "Sheetfile" "usb-c-interface.kicad_sch")
    (property "Sheetname" "USB-C Interface ")
    (property "Val" "100n")
    (property "Voltage" "50V")
    (attr smd)
    (fp_text reference "C92" (at 3.07 0.36 270) (layer "B.SilkS")
      (effects (font (size 0.7 0.7) (thickness 0.15)) (justify left bottom mirror))
    )
    (fp_text value "C_100n_0402" (at 0 -1.4 270) (layer "B.Fab")
      (effects (font (size 0.7 0.7) (thickness 0.15)) (justify left bottom mirror))
    )
    (fp_text user "Author: Antmicro" (at -0.932 -4.17 270) (layer "B.Fab") hide
      (effects (font (size 0.7 0.7) (thickness 0.15)) (justify left bottom mirror))
    )
    (fp_text user "License: Apache-2.0" (at -0.932 -5.17 270) (layer "B.Fab") hide
      (effects (font (size 0.7 0.7) (thickness 0.15)) (justify left bottom mirror))
    )
    (fp_text user "${REFERENCE}" (at -0.932 -3.168 270) (layer "B.Fab") hide
      (effects (font (size 0.7 0.7) (thickness 0.15)) (justify left bottom mirror))
    )
    (fp_rect (start -0.94 0.47) (end 0.94 -0.47) (layer "B.CrtYd") (width 0.05) (fill none))
    (fp_rect (start -0.499 0.249) (end 0.499 -0.249) (layer "B.Fab") (width 0.15) (fill none))
    (pad "1" smd roundrect (at -0.484 0 90) (size 0.59 0.64) (layers "B.Cu" "B.Paste" "B.Mask") (roundrect_rratio 0.25)
      (net 308 "/USB-C Interface /USB1C_RX0_C_P") (pintype "passive"))
    (pad "2" smd roundrect (at 0.484 0 90) (size 0.59 0.64) (layers "B.Cu" "B.Paste" "B.Mask") (roundrect_rratio 0.25)
      (net 69 "USB1_SS_RX0_P") (pintype "passive"))
  )
	(footprint "sa800u-baseboard-hw-footprints:MicroSD_DM3AT-SF-PEJM5" locked (layer "B.Cu")
    (tedit 600CE7C2)
    (at 131.331 90.998)
    (descr "Micro SD, SMD, right-angle, push-pull")
    (tags "Micro SD")
    (property "Author" "Antmicro")
    (property "License" "Apache-2.0")
    (property "MPN" "DM3AT-SF-PEJM5")
    (property "Manufacturer" "Hirose")
    (property "Sheetfile" "other-interfaces.kicad_sch")
    (property "Sheetname" "Other Interfaces")
    (attr smd)
    (fp_text reference "J8" (at -6.25 9.3 180) (layer "B.SilkS")
      (effects (font (size 0.7 0.7) (thickness 0.15)) (justify left bottom mirror))
    )
    (fp_text value "DM3AT-SF-PEJM5" (at 8.14 -6.17 -90) (layer "B.Fab")
      (effects (font (size 0.7 0.7) (thickness 0.15)) (justify left bottom mirror))
    )
    (fp_text user "License: Apache-2.0" (at -7.927 -16.698 180) (layer "B.Fab") hide
      (effects (font (size 0.7 0.7) (thickness 0.15)) (justify left bottom mirror))
    )
    (fp_text user "Author: Antmicro" (at -7.927 -15.498 180) (layer "B.Fab") hide
      (effects (font (size 0.7 0.7) (thickness 0.15)) (justify left bottom mirror))
    )
    (fp_text user "${REFERENCE}" (at -7.927 -17.898 180) (layer "B.Fab") hide
      (effects (font (size 0.7 0.7) (thickness 0.15)) (justify left bottom mirror))
    )
    (fp_line (start -5.971 -8.157) (end -4.111 -8.157) (layer "B.SilkS") (width 0.15))
    (fp_line (start 5.289 -8.157) (end 5.488 -7.959) (layer "B.SilkS") (width 0.15))
    (fp_line (start 6.967 8.11) (end 6.967 -5.897) (layer "B.SilkS") (width 0.15))
    (fp_line (start -3.9 -7.809) (end 2.47 -7.809) (layer "B.SilkS") (width 0.15))
    (fp_line (start -5.971 -8.157) (end -6.17 -7.959) (layer "B.SilkS") (width 0.15))
    (fp_line (start -7 8.11) (end -7 4.502) (layer "B.SilkS") (width 0.15))
    (fp_line (start 5.289 -8.157) (end 2.979 -8.157) (layer "B.SilkS") (width 0.15))
    (fp_line (start 5.049 8.11) (end 6.967 8.11) (layer "B.SilkS") (width 0.15))
    (fp_line (start -7 2.802) (end -7 -1.898) (layer "B.SilkS") (width 0.15))
    (fp_line (start 2.979 -8.157) (end 2.47 -7.809) (layer "B.SilkS") (width 0.15))
    (fp_line (start -3.9 -7.809) (end -3.9 -7.959) (layer "B.SilkS") (width 0.15))
    (fp_line (start -4.111 -8.157) (end -3.9 -7.959) (layer "B.SilkS") (width 0.15))
    (fp_line (start 5.488 -7.959) (end 5.749 -7.959) (layer "B.SilkS") (width 0.15))
    (fp_line (start -6.553 8.11) (end -7 8.11) (layer "B.SilkS") (width 0.15))
    (fp_line (start -7 -3.197) (end -7 -4.998) (layer "B.SilkS") (width 0.15))
    (fp_circle (center 3.19 8.71) (end 3.239 8.71) (layer "B.SilkS") (width 0.15) (fill solid))
    (fp_rect (start -7.7 8.9) (end 7.4 -8.6) (layer "B.CrtYd") (width 0.05) (fill none))
    (fp_line (start 5.049 -12.998) (end 5.049 -8.099) (layer "B.Fab") (width 0.15))
    (fp_line (start 5.459 -7.898) (end 6.898 -7.898) (layer "B.Fab") (width 0.15))
    (fp_line (start -5.451 -13.498) (end 4.549 -13.498) (layer "B.Fab") (width 0.15))
    (fp_line (start -3.94 -7.898) (end -3.94 -7.748) (layer "B.Fab") (width 0.15))
    (fp_line (start -6.141 -7.898) (end -6.951 -7.898) (layer "B.Fab") (width 0.15))
    (fp_line (start -5.941 -8.099) (end -6.141 -7.898) (layer "B.Fab") (width 0.15))
    (fp_line (start -4.141 -8.099) (end -5.941 -8.099) (layer "B.Fab") (width 0.15))
    (fp_line (start 5.259 -8.099) (end 3.01 -8.099) (layer "B.Fab") (width 0.15))
    (fp_line (start -3.94 -7.898) (end -4.141 -8.099) (layer "B.Fab") (width 0.15))
    (fp_line (start 3.01 -8.099) (end 2.483 -7.748) (layer "B.Fab") (width 0.15))
    (fp_line (start 6.898 -7.898) (end 6.898 8.051) (layer "B.Fab") (width 0.15))
    (fp_line (start 5.259 -8.099) (end 5.459 -7.898) (layer "B.Fab") (width 0.15))
    (fp_line (start -5.451 -9.497) (end 4.549 -9.497) (layer "B.Fab") (width 0.15))
    (fp_line (start 6.898 8.051) (end -6.951 8.051) (layer "B.Fab") (width 0.15))
    (fp_line (start -5.951 -8.099) (end -5.951 -12.998) (layer "B.Fab") (width 0.15))
    (fp_line (start 2.483 -7.748) (end -3.94 -7.748) (layer "B.Fab") (width 0.15))
    (fp_line (start -6.951 -7.898) (end -6.951 8.051) (layer "B.Fab") (width 0.15))
    (fp_arc (start 4.549 -9.497) (mid 4.903498 -9.351498) (end 5.049 -8.997) (layer "B.Fab") (width 0.15))
    (fp_arc (start -5.951 -12.998) (mid -5.805 -13.352) (end -5.451 -13.498) (layer "B.Fab") (width 0.15))
    (fp_arc (start 4.549 -13.498) (mid 4.902994 -13.351994) (end 5.049 -12.998) (layer "B.Fab") (width 0.15))
    (fp_arc (start -5.951 -8.997) (mid -5.8055 -9.3515) (end -5.451 -9.497) (layer "B.Fab") (width 0.15))
    (pad "1" smd rect locked (at 2.749 7.952) (size 0.7 1.2) (layers "B.Cu" "B.Paste" "B.Mask")
      (net 247 "/Other Interfaces/SD_DATA2_R") (pinfunction "DAT2") (pintype "bidirectional"))
    (pad "2" smd rect locked (at 1.65 7.952) (size 0.7 1.2) (layers "B.Cu" "B.Paste" "B.Mask")
      (net 249 "/Other Interfaces/SD_DATA3_R") (pinfunction "DAT3/CD") (pintype "bidirectional"))
    (pad "3" smd rect locked (at 0.549 7.952) (size 0.7 1.2) (layers "B.Cu" "B.Paste" "B.Mask")
      (net 248 "/Other Interfaces/SD_CMD_R") (pinfunction "CMD") (pintype "input"))
    (pad "4" smd rect locked (at -0.552 7.952) (size 0.7 1.2) (layers "B.Cu" "B.Paste" "B.Mask")
      (net 227 "/Other Interfaces/SD_VDD_R") (pinfunction "VDD") (pintype "power_in"))
    (pad "5" smd rect locked (at -1.651 7.952) (size 0.7 1.2) (layers "B.Cu" "B.Paste" "B.Mask")
      (net 250 "/Other Interfaces/SD_CLK_R") (pinfunction "CLK") (pintype "input"))
    (pad "6" smd rect locked (at -2.751 7.952) (size 0.7 1.2) (layers "B.Cu" "B.Paste" "B.Mask")
      (net 1 "GND") (pinfunction "VSS") (pintype "power_in"))
    (pad "7" smd rect locked (at -3.851 7.952) (size 0.7 1.2) (layers "B.Cu" "B.Paste" "B.Mask")
      (net 252 "/Other Interfaces/SD_DATA0_R") (pinfunction "DAT0") (pintype "input"))
    (pad "8" smd rect locked (at -4.951 7.952) (size 0.7 1.2) (layers "B.Cu" "B.Paste" "B.Mask")
      (net 251 "/Other Interfaces/SD_DATA1_R") (pinfunction "DAT1") (pintype "input"))
    (pad "9" smd rect locked (at -5.901 7.952) (size 0.7 1.2) (layers "B.Cu" "B.Paste" "B.Mask")
      (net 1 "GND") (pinfunction "DET_B") (pintype "passive"))
    (pad "10" smd rect locked (at -6.851 -2.547) (size 1 0.8) (layers "B.Cu" "B.Paste" "B.Mask")
      (net 246 "/Other Interfaces/SD_DET_R") (pinfunction "DET_A") (pintype "passive"))
    (pad "11" smd rect locked (at 4.299 7.952) (size 1 1.2) (layers "B.Cu" "B.Paste" "B.Mask")
      (net 1 "GND") (pinfunction "SHIELD") (pintype "passive"))
    (pad "11" smd rect locked (at -6.851 3.652) (size 1 1.2) (layers "B.Cu" "B.Paste" "B.Mask")
      (net 1 "GND") (pinfunction "SHIELD") (pintype "passive"))
    (pad "11" smd rect locked (at -6.851 -6.698) (size 1 2.8) (layers "B.Cu" "B.Paste" "B.Mask")
      (net 1 "GND") (pinfunction "SHIELD") (pintype "passive"))
    (pad "11" smd rect locked (at 6.648 -7.148) (size 1.3 1.9) (layers "B.Cu" "B.Paste" "B.Mask")
      (net 1 "GND") (pinfunction "SHIELD") (pintype "passive"))
  )
	(footprint "sa800u-baseboard-hw-footprints:R_0402_1005Metric" (layer "B.Cu")
    (tedit 5FD9C158)
    (at 121.88 93.8 90)
    (descr "Resistor SMD 0402")
    (tags "resistor SMD 0402")
    (property "Author" "Antmicro")
    (property "DNP" "DNP")
    (property "License" "Apache-2.0")
    (property "MPN" "CR0402-FX-1003GLF")
    (property "Manufacturer" "Bourns")
    (property "Sheetfile" "other-interfaces.kicad_sch")
    (property "Sheetname" "Other Interfaces")
    (property "Tolerance" "1%")
    (property "Val" "100k")
    (attr exclude_from_pos_files)
    (fp_text reference "R94" (at -0.87 0.5 270) (layer "B.SilkS")
      (effects (font (size 0.7 0.7) (thickness 0.15)) (justify left bottom mirror))
    )
    (fp_text value "R_100k_0402" (at 0 -1.4 270) (layer "B.Fab")
      (effects (font (size 0.7 0.7) (thickness 0.15)) (justify left bottom mirror))
    )
    (fp_text user "Author: Antmicro" (at -0.95 -4.169 270) (layer "B.Fab") hide
      (effects (font (size 0.7 0.7) (thickness 0.15)) (justify left bottom mirror))
    )
    (fp_text user "License: Apache-2.0" (at -0.95 -5.169 270) (layer "B.Fab") hide
      (effects (font (size 0.7 0.7) (thickness 0.15)) (justify left bottom mirror))
    )
    (fp_text user "${REFERENCE}" (at -0.95 -3.168 270) (layer "B.Fab") hide
      (effects (font (size 0.7 0.7) (thickness 0.15)) (justify left bottom mirror))
    )
    (fp_rect (start -0.93 0.47) (end 0.93 -0.47) (layer "B.CrtYd") (width 0.05) (fill none))
    (fp_rect (start -0.5 0.25) (end 0.5 -0.25) (layer "B.Fab") (width 0.15) (fill none))
    (pad "1" smd roundrect (at -0.485 0 90) (size 0.59 0.64) (layers "B.Cu" "B.Paste" "B.Mask") (roundrect_rratio 0.25)
      (net 132 "VREG_S4A_1V8") (pintype "passive"))
    (pad "2" smd roundrect (at 0.485 0 90) (size 0.59 0.64) (layers "B.Cu" "B.Paste" "B.Mask") (roundrect_rratio 0.25)
      (net 112 "SD_DET") (pintype "passive"))
  )
)
